(kicad_pcb
	(version 20241229)
	(generator "pcbnew")
	(generator_version "9.0")
	(general
		(thickness 1.61)
		(legacy_teardrops no)
	)
	(paper "A3")
	(title_block
		(title "RDIMM DDR5 Tester")
		(date "2026-05-21")
		(rev "2.2.0")
		(company "Antmicro")
		(comment 9 "footprints 277-278 of 796")
	)
	(layers
		(0 "F.Cu" signal)
		(4 "In1.Cu" power)
		(6 "In2.Cu" mixed)
		(8 "In3.Cu" power)
		(10 "In4.Cu" mixed)
		(12 "In5.Cu" power)
		(14 "In6.Cu" mixed)
		(16 "In7.Cu" power)
		(18 "In8.Cu" power)
		(20 "In9.Cu" mixed)
		(22 "In10.Cu" power)
		(2 "B.Cu" signal)
		(9 "F.Adhes" user "F.Adhesive")
		(11 "B.Adhes" user "B.Adhesive")
		(13 "F.Paste" user)
		(15 "B.Paste" user)
		(5 "F.SilkS" user "F.Silkscreen")
		(7 "B.SilkS" user "B.Silkscreen")
		(1 "F.Mask" user)
		(3 "B.Mask" user)
		(17 "Dwgs.User" user "User.Drawings")
		(19 "Cmts.User" user "User.Comments")
		(21 "Eco1.User" user "User.Eco1")
		(23 "Eco2.User" user "User.Eco2")
		(25 "Edge.Cuts" user)
		(27 "Margin" user)
		(31 "F.CrtYd" user "F.Courtyard")
		(29 "B.CrtYd" user "B.Courtyard")
		(35 "F.Fab" user)
		(33 "B.Fab" user)
	)
	(footprint "antmicro-footprints:SC70-3"
		(layer "F.Cu")
		(at 118.1 115.1 90)
		(property "Reference" "Q3"
			(at -0.425 -0.775 180)
			(layer "F.SilkS")
			(effects
				(font
					(size 0.7 0.7)
					(thickness 0.15)
				)
				(justify left bottom)
			)
		)
		(property "Value" "BSS138PW"
			(at 0 2.3 90)
			(layer "F.Fab")
			(effects
				(font
					(size 0.7 0.7)
					(thickness 0.15)
				)
				(justify left bottom)
			)
		)
		(property "Datasheet" "https://assets.nexperia.com/documents/data-sheet/BSS138PW.pdf"
			(at 0 0 90)
			(layer "F.Fab")
			(hide yes)
			(effects
				(font
					(size 1.27 1.27)
					(thickness 0.15)
				)
			)
		)
		(property "MPN" "BSS138PW"
			(at 0 0 90)
			(unlocked yes)
			(layer "F.Fab")
			(hide yes)
			(effects
				(font
					(size 1 1)
					(thickness 0.15)
				)
			)
		)
		(property "Manufacturer" "Nexperia"
			(at 0 0 90)
			(unlocked yes)
			(layer "F.Fab")
			(hide yes)
			(effects
				(font
					(size 1 1)
					(thickness 0.15)
				)
			)
		)
		(property "Author" "Antmicro"
			(at 0 0 90)
			(unlocked yes)
			(layer "F.Fab")
			(hide yes)
			(effects
				(font
					(size 1 1)
					(thickness 0.15)
				)
			)
		)
		(property "License" "Apache-2.0"
			(at 0 0 90)
			(unlocked yes)
			(layer "F.Fab")
			(hide yes)
			(effects
				(font
					(size 1 1)
					(thickness 0.15)
				)
			)
		)
		(sheetname "/FPGA Config/")
		(sheetfile "fpga-config.kicad_sch")
		(attr smd)
		(fp_line
			(start -0.3 -1)
			(end 0.627 -0.999)
			(stroke
				(width 0.15)
				(type solid)
			)
			(layer "F.SilkS")
		)
		(fp_line
			(start 0.627 -0.6)
			(end 0.627 -0.999)
			(stroke
				(width 0.15)
				(type solid)
			)
			(layer "F.SilkS")
		)
		(fp_line
			(start 0.627 0.6)
			(end 0.627 1.001)
			(stroke
				(width 0.15)
				(type solid)
			)
			(layer "F.SilkS")
		)
		(fp_line
			(start -0.3 1)
			(end 0.627 1.001)
			(stroke
				(width 0.15)
				(type solid)
			)
			(layer "F.SilkS")
		)
		(fp_line
			(start 0.9 -1.3)
			(end 0.9 -0.4)
			(stroke
				(width 0.05)
				(type solid)
			)
			(layer "F.CrtYd")
		)
		(fp_line
			(start -0.9 -1.3)
			(end 0.9 -1.3)
			(stroke
				(width 0.05)
				(type solid)
			)
			(layer "F.CrtYd")
		)
		(fp_line
			(start -0.9 -1.3)
			(end -0.9 -1)
			(stroke
				(width 0.05)
				(type solid)
			)
			(layer "F.CrtYd")
		)
		(fp_line
			(start -0.9 -1)
			(end -1.4 -1)
			(stroke
				(width 0.05)
				(type solid)
			)
			(layer "F.CrtYd")
		)
		(fp_line
			(start 1.4 -0.4)
			(end 1.4 0.4)
			(stroke
				(width 0.05)
				(type solid)
			)
			(layer "F.CrtYd")
		)
		(fp_line
			(start 0.9 -0.4)
			(end 1.4 -0.4)
			(stroke
				(width 0.05)
				(type solid)
			)
			(layer "F.CrtYd")
		)
		(fp_line
			(start 1.4 0.4)
			(end 0.9 0.4)
			(stroke
				(width 0.05)
				(type solid)
			)
			(layer "F.CrtYd")
		)
		(fp_line
			(start 0.9 0.4)
			(end 0.9 1.3)
			(stroke
				(width 0.05)
				(type solid)
			)
			(layer "F.CrtYd")
		)
		(fp_line
			(start -0.9 1)
			(end -1.4 1)
			(stroke
				(width 0.05)
				(type solid)
			)
			(layer "F.CrtYd")
		)
		(fp_line
			(start -1.4 1)
			(end -1.4 -1)
			(stroke
				(width 0.05)
				(type solid)
			)
			(layer "F.CrtYd")
		)
		(fp_line
			(start 0.9 1.3)
			(end -0.9 1.3)
			(stroke
				(width 0.05)
				(type solid)
			)
			(layer "F.CrtYd")
		)
		(fp_line
			(start -0.9 1.3)
			(end -0.9 1)
			(stroke
				(width 0.05)
				(type solid)
			)
			(layer "F.CrtYd")
		)
		(fp_rect
			(start -0.623 -0.999)
			(end 0.627 1.001)
			(stroke
				(width 0.15)
				(type solid)
			)
			(fill no)
			(layer "F.Fab")
		)
		(fp_text user "License: Apache-2.0"
			(at -1.45 6.782 90)
			(layer "F.Fab")
			(effects
				(font
					(size 0.7 0.7)
					(thickness 0.15)
				)
				(justify left bottom)
			)
		)
		(fp_text user "${REFERENCE}"
			(at -1.45 4.783 90)
			(layer "F.Fab")
			(effects
				(font
					(size 0.7 0.7)
					(thickness 0.15)
				)
				(justify left bottom)
			)
		)
		(fp_text user "Author: Antmicro"
			(at -1.45 5.782 90)
			(layer "F.Fab")
			(effects
				(font
					(size 0.7 0.7)
					(thickness 0.15)
				)
				(justify left bottom)
			)
		)
		(pad "1" smd rect
			(at -1.051 -0.65 180)
			(size 0.6 0.6)
			(layers "F.Cu" "F.Mask" "F.Paste")
			(net 340 "/FPGA Config/DONE")
			(pinfunction "G")
			(pintype "passive")
		)
		(pad "2" smd rect
			(at -1.051 0.65 180)
			(size 0.6 0.6)
			(layers "F.Cu" "F.Mask" "F.Paste")
			(net 1 "GND")
			(pinfunction "S")
			(pintype "passive")
		)
		(pad "3" smd rect
			(at 1.05 0 180)
			(size 0.6 0.6)
			(layers "F.Cu" "F.Mask" "F.Paste")
			(net 271 "Net-(Q3-D)")
			(pinfunction "D")
			(pintype "passive")
		)
	)
	(footprint "antmicro-footprints:L_0402_1005Metric"
		(layer "F.Cu")
		(at 121.025 150.61 180)
		(descr "Inductor SMD 0402")
		(tags "Inductor SMD 0402")
		(property "Reference" "L5"
			(at -5.375 -0.435 0)
			(layer "F.SilkS")
			(effects
				(font
					(size 0.7 0.7)
					(thickness 0.15)
				)
				(justify right bottom)
			)
		)
		(property "Value" "L_20n_0.35A_0402"
			(at 0 1.4 0)
			(layer "F.Fab")
			(effects
				(font
					(size 0.7 0.7)
					(thickness 0.15)
				)
				(justify right bottom)
			)
		)
		(property "Datasheet" "https://product.tdk.com/system/files/dam/doc/product/inductor/inductor/smd/catalog/inductor_automotive_high-frequency_mlg1005s_en.pdf?ref_disty=mouser"
			(at 0 0 180)
			(layer "F.Fab")
			(hide yes)
			(effects
				(font
					(size 1.27 1.27)
					(thickness 0.15)
				)
			)
		)
		(property "Val" "20n/0.35A"
			(at 0 0 180)
			(unlocked yes)
			(layer "F.Fab")
			(hide yes)
			(effects
				(font
					(size 1 1)
					(thickness 0.15)
				)
			)
		)
		(property "Manufacturer" "TDK"
			(at 0 0 180)
			(unlocked yes)
			(layer "F.Fab")
			(hide yes)
			(effects
				(font
					(size 1 1)
					(thickness 0.15)
				)
			)
		)
		(property "MPN" "MLG1005S20NJTD25"
			(at 0 0 180)
			(unlocked yes)
			(layer "F.Fab")
			(hide yes)
			(effects
				(font
					(size 1 1)
					(thickness 0.15)
				)
			)
		)
		(property "ISat" ""
			(at 0 0 180)
			(unlocked yes)
			(layer "F.Fab")
			(hide yes)
			(effects
				(font
					(size 1 1)
					(thickness 0.15)
				)
			)
		)
		(property "IMax" "0.35 A"
			(at 0 0 180)
			(unlocked yes)
			(layer "F.Fab")
			(hide yes)
			(effects
				(font
					(size 1 1)
					(thickness 0.15)
				)
			)
		)
		(property "Size" "1.0x0.5"
			(at 0 0 180)
			(unlocked yes)
			(layer "F.Fab")
			(hide yes)
			(effects
				(font
					(size 1 1)
					(thickness 0.15)
				)
			)
		)
		(property "Author" "Antmicro"
			(at 0 0 180)
			(unlocked yes)
			(layer "F.Fab")
			(hide yes)
			(effects
				(font
					(size 1 1)
					(thickness 0.15)
				)
			)
		)
		(property "License" "Apache-2.0"
			(at 0 0 180)
			(unlocked yes)
			(layer "F.Fab")
			(hide yes)
			(effects
				(font
					(size 1 1)
					(thickness 0.15)
				)
			)
		)
		(sheetname "/HDMI + SD Card/")
		(sheetfile "hdmi-sd-card.kicad_sch")
		(attr smd)
		(fp_rect
			(start -0.925 -0.47)
			(end 0.925 0.47)
			(stroke
				(width 0.05)
				(type default)
			)
			(fill no)
			(layer "F.CrtYd")
		)
		(fp_rect
			(start -0.499 -0.249)
			(end 0.499 0.249)
			(stroke
				(width 0.15)
				(type solid)
			)
			(fill no)
			(layer "F.Fab")
		)
		(fp_text user "Author: Antmicro"
			(at -0.932 4.17 180)
			(layer "F.Fab")
			(effects
				(font
					(size 0.7 0.7)
					(thickness 0.15)
				)
				(justify left bottom)
			)
		)
		(fp_text user "License: Apache-2.0"
			(at -0.932 5.17 180)
			(layer "F.Fab")
			(effects
				(font
					(size 0.7 0.7)
					(thickness 0.15)
				)
				(justify left bottom)
			)
		)
		(fp_text user "${REFERENCE}"
			(at -0.932 3.168 180)
			(layer "F.Fab")
			(effects
				(font
					(size 0.7 0.7)
					(thickness 0.15)
				)
				(justify left bottom)
			)
		)
		(pad "1" smd roundrect
			(at -0.48 0 180)
			(size 0.59 0.64)
			(layers "F.Cu" "F.Mask" "F.Paste")
			(roundrect_rratio 0.25)
			(net 346 "/FPGA MGT Interface/HDMI_IN.D1_N")
			(pintype "passive")
		)
		(pad "2" smd roundrect
			(at 0.48 0 180)
			(size 0.59 0.64)
			(layers "F.Cu" "F.Mask" "F.Paste")
			(roundrect_rratio 0.25)
			(net 675 "Net-(L5-Pad2)")
			(pintype "passive")
		)
	)
)
